# S9S_MB_2U (Grand Teton) — schematic netlist excerpt (pin names and nets, part order shuffled) for the footprints in the layout excerpt that follows; sources: Cadence DE-HDL packaged netlist, KiCad conversion of 03242023_DA0F0TMBIJ0_F0T_Motherboard_J_brd_V01_OCP.brd

R2256  Q_RES  0 5% EMPTY  pkg 0402LF  page 240 : A = USB2_7_R_DP ; B = USB2_7_DP
C9  Q_CAP  10UF 16V 10% X6S  pkg C0805  page 84 : A = P12V_S3_AUX_CPU0_NVDIMM ; B = GND
C1923  Q_CAP  0.1UF 25V 10% X7R  pkg 0402  page 190 : A = P3V3_M2_0 ; B = GND

(kicad_pcb
	(version 20260206)
	(generator "pcbnew")
	(generator_version "10.0")
	(general
		(thickness 1.6)
		(legacy_teardrops no)
	)
	(paper "A4")
	(title_block
		(title "03242023_DA0F0TMBIJ0_F0T_Motherboard_J_brd_V01_OCP.brd")
		(comment 1 "Grand Teton / footprints 4870-4872 of 6105")
	)
	(layers
		(0 "F.Cu" signal "TOP")
		(4 "In1.Cu" signal "GND")
		(6 "In2.Cu" signal "IN1")
		(8 "In3.Cu" signal "GND1")
		(10 "In4.Cu" signal "IN2")
		(12 "In5.Cu" signal "GND2")
		(14 "In6.Cu" signal "IN3")
		(16 "In7.Cu" signal "GND3")
		(18 "In8.Cu" signal "VCC")
		(20 "In9.Cu" signal "VCC1")
		(22 "In10.Cu" signal "GND4")
		(24 "In11.Cu" signal "IN4")
		(26 "In12.Cu" signal "GND5")
		(28 "In13.Cu" signal "IN5")
		(30 "In14.Cu" signal "GND6")
		(32 "In15.Cu" signal "IN6")
		(34 "In16.Cu" signal "GND7")
		(2 "B.Cu" signal "BOTTOM")
		(9 "F.Adhes" user "F.Adhesive")
		(11 "B.Adhes" user "B.Adhesive")
		(13 "F.Paste" user "Package Geometry/Pastemask Top")
		(15 "B.Paste" user "Package Geometry/Pastemask Bottom")
		(5 "F.SilkS" user "Ref Des/Silkscreen Top")
		(7 "B.SilkS" user "Ref Des/Silkscreen Bottom")
		(1 "F.Mask" user "Board Geometry/Soldermask Top")
		(3 "B.Mask" user "Board Geometry/Soldermask Bottom")
		(17 "Dwgs.User" user "User.Drawings")
		(19 "Cmts.User" user "User.Comments")
		(21 "Eco1.User" user "User.Eco1")
		(23 "Eco2.User" user "User.Eco2")
		(25 "Edge.Cuts" user "Board Geometry/Outline")
		(27 "Margin" user)
		(31 "F.CrtYd" user "Package Geometry/Place Bound Top")
		(29 "B.CrtYd" user "Package Geometry/Place Bound Bottom")
		(35 "F.Fab" user "Ref Des/Assembly Top")
		(33 "B.Fab" user "Ref Des/Assembly Bottom")
	)
	(footprint ""
		(layer "B.Cu")
		(at 286.268414 -321.549776 -90)
		(property "Reference" "C9"
			(at 0 0 90)
			(layer "B.SilkS")
			(hide yes)
			(effects
				(font
					(size 1.27 1.27)
				)
				(justify mirror)
			)
		)
		(property "Value" ""
			(at 0 0 90)
			(layer "B.Fab")
			(effects
				(font
					(size 1.27 1.27)
				)
				(justify mirror)
			)
		)
		(duplicate_pad_numbers_are_jumpers no)
		(fp_line
			(start -1.524 0.762)
			(end 1.524 0.762)
			(stroke
				(width 0.1524)
				(type default)
			)
			(layer "B.SilkS")
		)
		(fp_line
			(start 1.524 0.762)
			(end 1.524 -0.762)
			(stroke
				(width 0.1524)
				(type default)
			)
			(layer "B.SilkS")
		)
		(fp_line
			(start -1.524 -0.762)
			(end -1.524 0.762)
			(stroke
				(width 0.1524)
				(type default)
			)
			(layer "B.SilkS")
		)
		(fp_line
			(start 1.524 -0.762)
			(end -1.524 -0.762)
			(stroke
				(width 0.1524)
				(type default)
			)
			(layer "B.SilkS")
		)
		(fp_line
			(start -1.1049 0.724916)
			(end -1.1049 -0.724916)
			(stroke
				(width 0.1)
				(type default)
			)
			(layer "B.Fab")
		)
		(fp_line
			(start 1.1049 0.724916)
			(end -1.1049 0.724916)
			(stroke
				(width 0.1)
				(type default)
			)
			(layer "B.Fab")
		)
		(fp_line
			(start -1.1049 -0.724916)
			(end 1.1049 -0.724916)
			(stroke
				(width 0.1)
				(type default)
			)
			(layer "B.Fab")
		)
		(fp_line
			(start 1.1049 -0.724916)
			(end 1.1049 0.724916)
			(stroke
				(width 0.1)
				(type default)
			)
			(layer "B.Fab")
		)
		(pad "1" smd rect
			(at 0.889 0 270)
			(size 1.016 1.27)
			(layers "B.Cu" "B.Mask" "B.Paste")
			(net "P12V_S3_AUX_CPU0_NVDIMM")
		)
		(pad "2" smd rect
			(at -0.889 0 270)
			(size 1.016 1.27)
			(layers "B.Cu" "B.Mask" "B.Paste")
			(net "GND")
		)
	)
	(footprint ""
		(layer "B.Cu")
		(at 187.096654 -19.417792 -90)
		(property "Reference" "R2256"
			(at 0 0 90)
			(layer "B.SilkS")
			(hide yes)
			(effects
				(font
					(size 1.27 1.27)
				)
				(justify mirror)
			)
		)
		(property "Value" ""
			(at 0 0 90)
			(layer "B.Fab")
			(effects
				(font
					(size 1.27 1.27)
				)
				(justify mirror)
			)
		)
		(duplicate_pad_numbers_are_jumpers no)
		(fp_line
			(start -0.361696 0.4064)
			(end 0.522224 0.4064)
			(stroke
				(width 0.1524)
				(type default)
			)
			(layer "B.SilkS")
		)
		(fp_line
			(start 0.7874 0.137414)
			(end 0.7874 -0.4064)
			(stroke
				(width 0.1524)
				(type default)
			)
			(layer "B.SilkS")
		)
		(fp_line
			(start -0.7874 -0.4064)
			(end -0.7874 -0.055626)
			(stroke
				(width 0.1524)
				(type default)
			)
			(layer "B.SilkS")
		)
		(fp_line
			(start 0.7874 -0.4064)
			(end -0.7874 -0.4064)
			(stroke
				(width 0.1524)
				(type default)
			)
			(layer "B.SilkS")
		)
		(fp_line
			(start -0.67945 0.3048)
			(end -0.120396 0.3048)
			(stroke
				(width 0.1)
				(type default)
			)
			(layer "B.Fab")
		)
		(fp_line
			(start -0.120396 0.3048)
			(end -0.120396 0.2794)
			(stroke
				(width 0.1)
				(type default)
			)
			(layer "B.Fab")
		)
		(fp_line
			(start 0.12065 0.3048)
			(end 0.67945 0.3048)
			(stroke
				(width 0.1)
				(type default)
			)
			(layer "B.Fab")
		)
		(fp_line
			(start 0.67945 0.3048)
			(end 0.67945 -0.305054)
			(stroke
				(width 0.1)
				(type default)
			)
			(layer "B.Fab")
		)
		(fp_line
			(start -0.120396 0.2794)
			(end 0.12065 0.2794)
			(stroke
				(width 0.1)
				(type default)
			)
			(layer "B.Fab")
		)
		(fp_line
			(start 0.12065 0.2794)
			(end 0.12065 0.3048)
			(stroke
				(width 0.1)
				(type default)
			)
			(layer "B.Fab")
		)
		(fp_line
			(start -0.12065 -0.2794)
			(end -0.12065 -0.3048)
			(stroke
				(width 0.1)
				(type default)
			)
			(layer "B.Fab")
		)
		(fp_line
			(start 0.12065 -0.2794)
			(end -0.12065 -0.2794)
			(stroke
				(width 0.1)
				(type default)
			)
			(layer "B.Fab")
		)
		(fp_line
			(start -0.67945 -0.3048)
			(end -0.67945 0.3048)
			(stroke
				(width 0.1)
				(type default)
			)
			(layer "B.Fab")
		)
		(fp_line
			(start -0.12065 -0.3048)
			(end -0.67945 -0.3048)
			(stroke
				(width 0.1)
				(type default)
			)
			(layer "B.Fab")
		)
		(fp_line
			(start 0.12065 -0.305054)
			(end 0.12065 -0.2794)
			(stroke
				(width 0.1)
				(type default)
			)
			(layer "B.Fab")
		)
		(fp_line
			(start 0.67945 -0.305054)
			(end 0.12065 -0.305054)
			(stroke
				(width 0.1)
				(type default)
			)
			(layer "B.Fab")
		)
		(pad "1" smd circle
			(at 0.40005 0 90)
			(size 0 0)
			(layers "B.Cu" "B.Mask" "B.Paste")
			(net "USB2_7_R_DP")
		)
		(pad "2" smd circle
			(at -0.40005 0 90)
			(size 0 0)
			(layers "B.Cu" "B.Mask" "B.Paste")
			(net "USB2_7_DP")
		)
	)
	(footprint ""
		(layer "B.Cu")
		(at 169.66692 -53.431948 180)
		(property "Reference" "C1923"
			(at 0 0 0)
			(layer "B.SilkS")
			(hide yes)
			(effects
				(font
					(size 1.27 1.27)
				)
				(justify mirror)
			)
		)
		(property "Value" ""
			(at 0 0 0)
			(layer "B.Fab")
			(effects
				(font
					(size 1.27 1.27)
				)
				(justify mirror)
			)
		)
		(duplicate_pad_numbers_are_jumpers no)
		(fp_line
			(start 0.7874 0.4064)
			(end 0.7874 -0.4064)
			(stroke
				(width 0.1524)
				(type default)
			)
			(layer "B.SilkS")
		)
		(fp_line
			(start 0.7874 -0.4064)
			(end -0.7874 -0.4064)
			(stroke
				(width 0.1524)
				(type default)
			)
			(layer "B.SilkS")
		)
		(fp_line
			(start -0.7874 0.4064)
			(end 0.7874 0.4064)
			(stroke
				(width 0.1524)
				(type default)
			)
			(layer "B.SilkS")
		)
		(fp_line
			(start -0.7874 -0.4064)
			(end -0.7874 0.4064)
			(stroke
				(width 0.1524)
				(type default)
			)
			(layer "B.SilkS")
		)
		(fp_line
			(start 0.67945 0.3048)
			(end 0.67945 -0.305054)
			(stroke
				(width 0.1)
				(type default)
			)
			(layer "B.Fab")
		)
		(fp_line
			(start 0.67945 -0.305054)
			(end 0.12065 -0.305054)
			(stroke
				(width 0.1)
				(type default)
			)
			(layer "B.Fab")
		)
		(fp_line
			(start 0.12065 0.3048)
			(end 0.67945 0.3048)
			(stroke
				(width 0.1)
				(type default)
			)
			(layer "B.Fab")
		)
		(fp_line
			(start 0.12065 0.2794)
			(end 0.12065 0.3048)
			(stroke
				(width 0.1)
				(type default)
			)
			(layer "B.Fab")
		)
		(fp_line
			(start 0.12065 -0.2794)
			(end -0.12065 -0.2794)
			(stroke
				(width 0.1)
				(type default)
			)
			(layer "B.Fab")
		)
		(fp_line
			(start 0.12065 -0.305054)
			(end 0.12065 -0.2794)
			(stroke
				(width 0.1)
				(type default)
			)
			(layer "B.Fab")
		)
		(fp_line
			(start -0.120396 0.3048)
			(end -0.120396 0.2794)
			(stroke
				(width 0.1)
				(type default)
			)
			(layer "B.Fab")
		)
		(fp_line
			(start -0.120396 0.2794)
			(end 0.12065 0.2794)
			(stroke
				(width 0.1)
				(type default)
			)
			(layer "B.Fab")
		)
		(fp_line
			(start -0.12065 -0.2794)
			(end -0.12065 -0.3048)
			(stroke
				(width 0.1)
				(type default)
			)
			(layer "B.Fab")
		)
		(fp_line
			(start -0.12065 -0.3048)
			(end -0.67945 -0.3048)
			(stroke
				(width 0.1)
				(type default)
			)
			(layer "B.Fab")
		)
		(fp_line
			(start -0.67945 0.3048)
			(end -0.120396 0.3048)
			(stroke
				(width 0.1)
				(type default)
			)
			(layer "B.Fab")
		)
		(fp_line
			(start -0.67945 -0.3048)
			(end -0.67945 0.3048)
			(stroke
				(width 0.1)
				(type default)
			)
			(layer "B.Fab")
		)
		(pad "1" smd circle
			(at 0.40005 0)
			(size 0 0)
			(layers "B.Cu" "B.Mask" "B.Paste")
			(net "P3V3_M2_0")
		)
		(pad "2" smd circle
			(at -0.40005 0)
			(size 0 0)
			(layers "B.Cu" "B.Mask" "B.Paste")
			(net "GND")
		)
	)
)
